# S9S_MB_2U (Grand Teton) — schematic netlist excerpt (pin names and nets, part order shuffled) for the footprints in the layout excerpt that follows; sources: Cadence DE-HDL packaged netlist, KiCad conversion of 03242023_DA0F0TMBIJ0_F0T_Motherboard_J_brd_V01_OCP.brd

PR4008  Q_RES  1.33K 1% EMPTY  pkg 0402LF  page 242 : A = P12V_SCM_SENSE ; B = GND
R4792  Q_RES  10K 1% EMPTY  pkg 0402LF  page 306 : A = P3V3_AUX ; B = OC_P2V5_COMP

(kicad_pcb
	(version 20260206)
	(generator "pcbnew")
	(generator_version "10.0")
	(general
		(thickness 1.6)
		(legacy_teardrops no)
	)
	(paper "A4")
	(title_block
		(title "03242023_DA0F0TMBIJ0_F0T_Motherboard_J_brd_V01_OCP.brd")
		(comment 1 "Grand Teton / footprints 3540-3541 of 6105")
	)
	(layers
		(0 "F.Cu" signal "TOP")
		(4 "In1.Cu" signal "GND")
		(6 "In2.Cu" signal "IN1")
		(8 "In3.Cu" signal "GND1")
		(10 "In4.Cu" signal "IN2")
		(12 "In5.Cu" signal "GND2")
		(14 "In6.Cu" signal "IN3")
		(16 "In7.Cu" signal "GND3")
		(18 "In8.Cu" signal "VCC")
		(20 "In9.Cu" signal "VCC1")
		(22 "In10.Cu" signal "GND4")
		(24 "In11.Cu" signal "IN4")
		(26 "In12.Cu" signal "GND5")
		(28 "In13.Cu" signal "IN5")
		(30 "In14.Cu" signal "GND6")
		(32 "In15.Cu" signal "IN6")
		(34 "In16.Cu" signal "GND7")
		(2 "B.Cu" signal "BOTTOM")
		(9 "F.Adhes" user "F.Adhesive")
		(11 "B.Adhes" user "B.Adhesive")
		(13 "F.Paste" user "Package Geometry/Pastemask Top")
		(15 "B.Paste" user "Package Geometry/Pastemask Bottom")
		(5 "F.SilkS" user "Ref Des/Silkscreen Top")
		(7 "B.SilkS" user "Ref Des/Silkscreen Bottom")
		(1 "F.Mask" user "Board Geometry/Soldermask Top")
		(3 "B.Mask" user "Board Geometry/Soldermask Bottom")
		(17 "Dwgs.User" user "User.Drawings")
		(19 "Cmts.User" user "User.Comments")
		(21 "Eco1.User" user "User.Eco1")
		(23 "Eco2.User" user "User.Eco2")
		(25 "Edge.Cuts" user "Board Geometry/Outline")
		(27 "Margin" user)
		(31 "F.CrtYd" user "Package Geometry/Place Bound Top")
		(29 "B.CrtYd" user "Package Geometry/Place Bound Bottom")
		(35 "F.Fab" user "Ref Des/Assembly Top")
		(33 "B.Fab" user "Ref Des/Assembly Bottom")
	)
	(footprint ""
		(layer "F.Cu")
		(at 180.79212 -411.20822 90)
		(property "Reference" "R4792"
			(at 0 0 90)
			(layer "F.SilkS")
			(hide yes)
			(effects
				(font
					(size 1.27 1.27)
				)
			)
		)
		(property "Value" ""
			(at 0 0 90)
			(layer "F.Fab")
			(effects
				(font
					(size 1.27 1.27)
				)
			)
		)
		(duplicate_pad_numbers_are_jumpers no)
		(fp_line
			(start 0.7874 -0.4064)
			(end 0.7874 0.4064)
			(stroke
				(width 0.1524)
				(type default)
			)
			(layer "F.SilkS")
		)
		(fp_line
			(start -0.7874 -0.4064)
			(end 0.7874 -0.4064)
			(stroke
				(width 0.1524)
				(type default)
			)
			(layer "F.SilkS")
		)
		(fp_line
			(start 0.7874 0.4064)
			(end -0.7874 0.4064)
			(stroke
				(width 0.1524)
				(type default)
			)
			(layer "F.SilkS")
		)
		(fp_line
			(start -0.7874 0.4064)
			(end -0.7874 -0.4064)
			(stroke
				(width 0.1524)
				(type default)
			)
			(layer "F.SilkS")
		)
		(fp_line
			(start -0.12065 -0.305054)
			(end -0.12065 -0.2794)
			(stroke
				(width 0.1)
				(type default)
			)
			(layer "F.Fab")
		)
		(fp_line
			(start -0.67945 -0.305054)
			(end -0.12065 -0.305054)
			(stroke
				(width 0.1)
				(type default)
			)
			(layer "F.Fab")
		)
		(fp_line
			(start 0.67945 -0.3048)
			(end 0.67945 0.3048)
			(stroke
				(width 0.1)
				(type default)
			)
			(layer "F.Fab")
		)
		(fp_line
			(start 0.12065 -0.3048)
			(end 0.67945 -0.3048)
			(stroke
				(width 0.1)
				(type default)
			)
			(layer "F.Fab")
		)
		(fp_line
			(start 0.12065 -0.2794)
			(end 0.12065 -0.3048)
			(stroke
				(width 0.1)
				(type default)
			)
			(layer "F.Fab")
		)
		(fp_line
			(start -0.12065 -0.2794)
			(end 0.12065 -0.2794)
			(stroke
				(width 0.1)
				(type default)
			)
			(layer "F.Fab")
		)
		(fp_line
			(start 0.120396 0.2794)
			(end -0.12065 0.2794)
			(stroke
				(width 0.1)
				(type default)
			)
			(layer "F.Fab")
		)
		(fp_line
			(start -0.12065 0.2794)
			(end -0.12065 0.3048)
			(stroke
				(width 0.1)
				(type default)
			)
			(layer "F.Fab")
		)
		(fp_line
			(start 0.67945 0.3048)
			(end 0.120396 0.3048)
			(stroke
				(width 0.1)
				(type default)
			)
			(layer "F.Fab")
		)
		(fp_line
			(start 0.120396 0.3048)
			(end 0.120396 0.2794)
			(stroke
				(width 0.1)
				(type default)
			)
			(layer "F.Fab")
		)
		(fp_line
			(start -0.12065 0.3048)
			(end -0.67945 0.3048)
			(stroke
				(width 0.1)
				(type default)
			)
			(layer "F.Fab")
		)
		(fp_line
			(start -0.67945 0.3048)
			(end -0.67945 -0.305054)
			(stroke
				(width 0.1)
				(type default)
			)
			(layer "F.Fab")
		)
		(pad "1" smd circle
			(at -0.40005 0 90)
			(size 0 0)
			(layers "F.Cu" "F.Mask" "F.Paste")
			(net "P3V3_AUX")
		)
		(pad "2" smd circle
			(at 0.40005 0 90)
			(size 0 0)
			(layers "F.Cu" "F.Mask" "F.Paste")
			(net "OC_P2V5_COMP")
		)
	)
	(footprint ""
		(layer "F.Cu")
		(at 185.928762 -26.788872 180)
		(property "Reference" "PR4008"
			(at 0 0 180)
			(layer "F.SilkS")
			(hide yes)
			(effects
				(font
					(size 1.27 1.27)
				)
			)
		)
		(property "Value" ""
			(at 0 0 180)
			(layer "F.Fab")
			(effects
				(font
					(size 1.27 1.27)
				)
			)
		)
		(duplicate_pad_numbers_are_jumpers no)
		(fp_line
			(start 0.7874 0.4064)
			(end -0.7874 0.4064)
			(stroke
				(width 0.1524)
				(type default)
			)
			(layer "F.SilkS")
		)
		(fp_line
			(start 0.7874 -0.4064)
			(end 0.7874 0.4064)
			(stroke
				(width 0.1524)
				(type default)
			)
			(layer "F.SilkS")
		)
		(fp_line
			(start -0.7874 0.4064)
			(end -0.7874 -0.4064)
			(stroke
				(width 0.1524)
				(type default)
			)
			(layer "F.SilkS")
		)
		(fp_line
			(start -0.7874 -0.4064)
			(end 0.7874 -0.4064)
			(stroke
				(width 0.1524)
				(type default)
			)
			(layer "F.SilkS")
		)
		(fp_line
			(start 0.67945 0.3048)
			(end 0.120396 0.3048)
			(stroke
				(width 0.1)
				(type default)
			)
			(layer "F.Fab")
		)
		(fp_line
			(start 0.67945 -0.3048)
			(end 0.67945 0.3048)
			(stroke
				(width 0.1)
				(type default)
			)
			(layer "F.Fab")
		)
		(fp_line
			(start 0.12065 -0.2794)
			(end 0.12065 -0.3048)
			(stroke
				(width 0.1)
				(type default)
			)
			(layer "F.Fab")
		)
		(fp_line
			(start 0.12065 -0.3048)
			(end 0.67945 -0.3048)
			(stroke
				(width 0.1)
				(type default)
			)
			(layer "F.Fab")
		)
		(fp_line
			(start 0.120396 0.3048)
			(end 0.120396 0.2794)
			(stroke
				(width 0.1)
				(type default)
			)
			(layer "F.Fab")
		)
		(fp_line
			(start 0.120396 0.2794)
			(end -0.12065 0.2794)
			(stroke
				(width 0.1)
				(type default)
			)
			(layer "F.Fab")
		)
		(fp_line
			(start -0.12065 0.3048)
			(end -0.67945 0.3048)
			(stroke
				(width 0.1)
				(type default)
			)
			(layer "F.Fab")
		)
		(fp_line
			(start -0.12065 0.2794)
			(end -0.12065 0.3048)
			(stroke
				(width 0.1)
				(type default)
			)
			(layer "F.Fab")
		)
		(fp_line
			(start -0.12065 -0.2794)
			(end 0.12065 -0.2794)
			(stroke
				(width 0.1)
				(type default)
			)
			(layer "F.Fab")
		)
		(fp_line
			(start -0.12065 -0.305054)
			(end -0.12065 -0.2794)
			(stroke
				(width 0.1)
				(type default)
			)
			(layer "F.Fab")
		)
		(fp_line
			(start -0.67945 0.3048)
			(end -0.67945 -0.305054)
			(stroke
				(width 0.1)
				(type default)
			)
			(layer "F.Fab")
		)
		(fp_line
			(start -0.67945 -0.305054)
			(end -0.12065 -0.305054)
			(stroke
				(width 0.1)
				(type default)
			)
			(layer "F.Fab")
		)
		(pad "1" smd circle
			(at -0.40005 0 180)
			(size 0 0)
			(layers "F.Cu" "F.Mask" "F.Paste")
			(net "P12V_SCM_SENSE")
		)
		(pad "2" smd circle
			(at 0.40005 0 180)
			(size 0 0)
			(layers "F.Cu" "F.Mask" "F.Paste")
			(net "GND")
		)
	)
)
